(kicad_pcb
	(version 20260206)
	(generator "pcbnew")
	(generator_version "10.0")
	(general
		(thickness 1.6)
		(legacy_teardrops no)
	)
	(paper "A4")
	(title_block
		(title "Bryce Canyon_IOM_IOC_16318-2_OCP.brd")
		(comment 1 "Bryce Canyon / footprints 238-240 of 1605")
	)
	(layers
		(0 "F.Cu" signal "TOP")
		(4 "In1.Cu" signal "L2GND")
		(6 "In2.Cu" signal "L3")
		(8 "In3.Cu" signal "L4VCC")
		(10 "In4.Cu" signal "L5VCC")
		(12 "In5.Cu" signal "L6")
		(14 "In6.Cu" signal "L7GND")
		(2 "B.Cu" signal "BOTTOM")
		(9 "F.Adhes" user "F.Adhesive")
		(11 "B.Adhes" user "B.Adhesive")
		(13 "F.Paste" user "Package Geometry/Pastemask Top")
		(15 "B.Paste" user "Package Geometry/Pastemask Bottom")
		(5 "F.SilkS" user "Ref Des/Silkscreen Top")
		(7 "B.SilkS" user "Ref Des/Silkscreen Bottom")
		(1 "F.Mask" user "Board Geometry/Soldermask Top")
		(3 "B.Mask" user "Board Geometry/Soldermask Bottom")
		(17 "Dwgs.User" user "User.Drawings")
		(19 "Cmts.User" user "User.Comments")
		(21 "Eco1.User" user "User.Eco1")
		(23 "Eco2.User" user "User.Eco2")
		(25 "Edge.Cuts" user "Board Geometry/Outline")
		(27 "Margin" user)
		(31 "F.CrtYd" user "Package Geometry/Place Bound Top")
		(29 "B.CrtYd" user "Package Geometry/Place Bound Bottom")
		(35 "F.Fab" user "Ref Des/Assembly Top")
		(33 "B.Fab" user "Ref Des/Assembly Bottom")
	)
	(footprint ""
		(layer "F.Cu")
		(at 52.59324 -160.38068)
		(property "Reference" "C86"
			(at 0 0 0)
			(layer "F.SilkS")
			(hide yes)
			(effects
				(font
					(size 1.27 1.27)
				)
			)
		)
		(property "Value" "SCD1U16V2KX-3GP"
			(at 1.1811 -2.7051 0)
			(unlocked yes)
			(layer "F.Fab")
			(hide yes)
			(effects
				(font
					(size 1.016 1.016)
					(thickness 0.1524)
				)
			)
		)
		(property "Device Type" "C402H22"
			(at 1.1811 -4.2291 0)
			(unlocked yes)
			(layer "F.Fab")
			(hide yes)
			(effects
				(font
					(size 1.016 1.016)
					(thickness 0.1524)
				)
			)
		)
		(duplicate_pad_numbers_are_jumpers no)
		(fp_rect
			(start -0.4318 0.9525)
			(end 0.4318 -0.9525)
			(stroke
				(width 0)
				(type default)
			)
			(fill no)
			(layer "F.CrtYd")
		)
		(fp_rect
			(start -0.4318 0.9525)
			(end 0.4318 -0.9525)
			(stroke
				(width 0)
				(type default)
			)
			(fill no)
			(layer "F.Fab")
		)
		(pad "1" smd custom
			(at 0 -0.4445)
			(size 0.1524 0.1524)
			(layers "F.Cu" "F.Mask" "F.Paste")
			(net "ADCVREFFN")
			(options
				(clearance outline)
				(anchor circle)
			)
			(primitives
				(gr_poly
					(pts
						(arc
							(start 0.3048 -0.2032)
							(mid 0.275042 -0.275042)
							(end 0.2032 -0.3048)
						)
						(arc
							(start -0.2032 -0.3048)
							(mid -0.275042 -0.275042)
							(end -0.3048 -0.2032)
						)
						(arc
							(start -0.3048 0.2032)
							(mid -0.275042 0.275042)
							(end -0.2032 0.3048)
						)
						(arc
							(start 0.2032 0.3048)
							(mid 0.275042 0.275042)
							(end 0.3048 0.2032)
						)
					)
					(width 0)
					(fill yes)
				)
			)
		)
		(pad "2" smd custom
			(at 0 0.4445)
			(size 0.1524 0.1524)
			(layers "F.Cu" "F.Mask" "F.Paste")
			(net "ADCVREFFP")
			(options
				(clearance outline)
				(anchor circle)
			)
			(primitives
				(gr_poly
					(pts
						(arc
							(start 0.3048 -0.2032)
							(mid 0.275042 -0.275042)
							(end 0.2032 -0.3048)
						)
						(arc
							(start -0.2032 -0.3048)
							(mid -0.275042 -0.275042)
							(end -0.3048 -0.2032)
						)
						(arc
							(start -0.3048 0.2032)
							(mid -0.275042 0.275042)
							(end -0.2032 0.3048)
						)
						(arc
							(start 0.2032 0.3048)
							(mid 0.275042 0.275042)
							(end 0.3048 0.2032)
						)
					)
					(width 0)
					(fill yes)
				)
			)
		)
	)
	(footprint ""
		(layer "F.Cu")
		(at 174.1424 -38.4556)
		(property "Reference" "TP176"
			(at 0 0 0)
			(layer "F.SilkS")
			(hide yes)
			(effects
				(font
					(size 1.27 1.27)
				)
			)
		)
		(property "Value" "TPAD28-2-GP"
			(at -0.0127 -1.6637 0)
			(unlocked yes)
			(layer "F.Fab")
			(hide yes)
			(effects
				(font
					(size 1.016 1.016)
					(thickness 0.1524)
				)
			)
		)
		(property "Device Type" "TPAD28"
			(at -0.0127 -3.1877 0)
			(unlocked yes)
			(layer "F.Fab")
			(hide yes)
			(effects
				(font
					(size 1.016 1.016)
					(thickness 0.1524)
				)
			)
		)
		(duplicate_pad_numbers_are_jumpers no)
		(fp_poly
			(pts
				(arc
					(start 0.3556 0)
					(mid -0.3556 0)
					(end 0.3556 0)
				)
			)
			(stroke
				(width 0)
				(type default)
			)
			(fill no)
			(layer "F.CrtYd")
		)
		(fp_poly
			(pts
				(arc
					(start 0.6096 0)
					(mid -0.6096 0)
					(end 0.6096 0)
				)
			)
			(stroke
				(width 0)
				(type default)
			)
			(fill no)
			(layer "F.Fab")
		)
		(pad "1" smd circle
			(at 0 0)
			(size 0.7112 0.7112)
			(layers "F.Cu" "F.Mask" "F.Paste")
			(net "ZDEF_EXTA_TP_B2")
		)
	)
	(footprint ""
		(layer "F.Cu")
		(at 217.822526 -98.204782 180)
		(property "Reference" "R603"
			(at 0 0 180)
			(layer "F.SilkS")
			(hide yes)
			(effects
				(font
					(size 1.27 1.27)
				)
			)
		)
		(property "Value" "4K7R2F-GP"
			(at 0.064008 -3.993896 180)
			(unlocked yes)
			(layer "F.Fab")
			(hide yes)
			(effects
				(font
					(size 1.016 1.016)
					(thickness 0.1524)
				)
			)
		)
		(property "Device Type" "R402H16"
			(at 0.064008 -5.517896 180)
			(unlocked yes)
			(layer "F.Fab")
			(hide yes)
			(effects
				(font
					(size 1.016 1.016)
					(thickness 0.1524)
				)
			)
		)
		(duplicate_pad_numbers_are_jumpers no)
		(fp_line
			(start 0.508 -0.9398)
			(end -0.508 -0.9398)
			(stroke
				(width 0.1524)
				(type default)
			)
			(layer "F.SilkS")
		)
		(fp_line
			(start -0.508 -0.9398)
			(end -0.508 0.9398)
			(stroke
				(width 0.1524)
				(type default)
			)
			(layer "F.SilkS")
		)
		(fp_rect
			(start -0.508 0.9398)
			(end 0.508 -0.9398)
			(stroke
				(width 0)
				(type default)
			)
			(fill no)
			(layer "F.CrtYd")
		)
		(fp_rect
			(start -0.508 0.9398)
			(end 0.508 -0.9398)
			(stroke
				(width 0)
				(type default)
			)
			(fill no)
			(layer "F.Fab")
		)
		(pad "1" smd custom
			(at 0 -0.4445 180)
			(size 0.1397 0.1397)
			(layers "F.Cu" "F.Mask" "F.Paste")
			(net "IOC_EEPROM_A0")
			(options
				(clearance outline)
				(anchor circle)
			)
			(primitives
				(gr_poly
					(pts
						(arc
							(start -0.1778 -0.2794)
							(mid -0.249642 -0.249642)
							(end -0.2794 -0.1778)
						)
						(arc
							(start -0.2794 0.1778)
							(mid -0.249642 0.249642)
							(end -0.1778 0.2794)
						)
						(arc
							(start 0.1778 0.2794)
							(mid 0.249642 0.249642)
							(end 0.2794 0.1778)
						)
						(arc
							(start 0.2794 -0.1778)
							(mid 0.249642 -0.249642)
							(end 0.1778 -0.2794)
						)
					)
					(width 0)
					(fill yes)
				)
			)
		)
		(pad "2" smd custom
			(at 0 0.4445 180)
			(size 0.1397 0.1397)
			(layers "F.Cu" "F.Mask" "F.Paste")
			(net "GND")
			(options
				(clearance outline)
				(anchor circle)
			)
			(primitives
				(gr_poly
					(pts
						(arc
							(start -0.1778 -0.2794)
							(mid -0.249642 -0.249642)
							(end -0.2794 -0.1778)
						)
						(arc
							(start -0.2794 0.1778)
							(mid -0.249642 0.249642)
							(end -0.1778 0.2794)
						)
						(arc
							(start 0.1778 0.2794)
							(mid 0.249642 0.249642)
							(end 0.2794 0.1778)
						)
						(arc
							(start 0.2794 -0.1778)
							(mid 0.249642 -0.249642)
							(end 0.1778 -0.2794)
						)
					)
					(width 0)
					(fill yes)
				)
			)
		)
	)
)
